(kicad_pcb
	(version 20241229)
	(generator "pcbnew")
	(generator_version "9.0")
	(general
		(thickness 1.599998)
		(legacy_teardrops no)
	)
	(paper "A4")
	(title_block
		(title "Artix - Datacenter Secure Control Module (DC-SCM)")
		(date "2024-11-06")
		(rev "1.1.3")
		(comment 9 "footprints 314-318 of 544")
	)
	(layers
		(0 "F.Cu" signal)
		(4 "In1.Cu" signal)
		(6 "In2.Cu" signal)
		(8 "In3.Cu" signal)
		(10 "In4.Cu" signal)
		(12 "In5.Cu" signal)
		(14 "In6.Cu" signal)
		(2 "B.Cu" signal)
		(9 "F.Adhes" user "F.Adhesive")
		(11 "B.Adhes" user "B.Adhesive")
		(13 "F.Paste" user)
		(15 "B.Paste" user)
		(5 "F.SilkS" user "F.Silkscreen")
		(7 "B.SilkS" user "B.Silkscreen")
		(1 "F.Mask" user)
		(3 "B.Mask" user)
		(17 "Dwgs.User" user "User.Drawings")
		(19 "Cmts.User" user "User.Comments")
		(21 "Eco1.User" user "User.Eco1")
		(23 "Eco2.User" user "User.Eco2")
		(25 "Edge.Cuts" user)
		(27 "Margin" user)
		(31 "F.CrtYd" user "F.Courtyard")
		(29 "B.CrtYd" user "B.Courtyard")
		(35 "F.Fab" user)
		(33 "B.Fab" user)
	)
	(footprint "antmicro-footprints:C_0402_1005Metric"
		(layer "B.Cu")
		(at 95.575 112.675 180)
		(descr "Capacitor SMD 0402")
		(tags "capacitor SMD 0402")
		(property "Reference" "C128"
			(at -1.425 0.475 0)
			(layer "B.SilkS")
			(effects
				(font
					(size 0.7 0.7)
					(thickness 0.15)
				)
				(justify left bottom mirror)
			)
		)
		(property "Value" "C_470n_0402"
			(at 0 -1.4 0)
			(layer "B.Fab")
			(effects
				(font
					(size 0.7 0.7)
					(thickness 0.15)
				)
				(justify left bottom mirror)
			)
		)
		(property "Datasheet" "https://product.tdk.com/en/search/capacitor/ceramic/mlcc/info?part_no=C1005X5R1E474M050BB"
			(at 0 0 180)
			(layer "F.Fab")
			(hide yes)
			(effects
				(font
					(size 1.27 1.27)
					(thickness 0.15)
				)
			)
		)
		(property "Description" "SMD Multilayer Ceramic Capacitor, 0.47 µF, 25 V, 0402 [1005 Metric], ± 20%, X5R, C"
			(at 0 0 180)
			(layer "F.Fab")
			(hide yes)
			(effects
				(font
					(size 1.27 1.27)
					(thickness 0.15)
				)
			)
		)
		(property "Author" "Antmicro"
			(at 191.15 225.35 0)
			(layer "B.Fab")
			(hide yes)
			(effects
				(font
					(size 1 1)
					(thickness 0.15)
				)
				(justify mirror)
			)
		)
		(property "Dielectric" ""
			(at 191.15 225.35 0)
			(layer "B.Fab")
			(hide yes)
			(effects
				(font
					(size 1 1)
					(thickness 0.15)
				)
				(justify mirror)
			)
		)
		(property "License" "Apache-2.0"
			(at 191.15 225.35 0)
			(layer "B.Fab")
			(hide yes)
			(effects
				(font
					(size 1 1)
					(thickness 0.15)
				)
				(justify mirror)
			)
		)
		(property "MPN" "C1005X5R1E474M050BB"
			(at 191.15 225.35 0)
			(layer "B.Fab")
			(hide yes)
			(effects
				(font
					(size 1 1)
					(thickness 0.15)
				)
				(justify mirror)
			)
		)
		(property "Manufacturer" "TDK"
			(at 191.15 225.35 0)
			(layer "B.Fab")
			(hide yes)
			(effects
				(font
					(size 1 1)
					(thickness 0.15)
				)
				(justify mirror)
			)
		)
		(property "Val" "470n"
			(at 191.15 225.35 0)
			(layer "B.Fab")
			(hide yes)
			(effects
				(font
					(size 1 1)
					(thickness 0.15)
				)
				(justify mirror)
			)
		)
		(property "Voltage" ""
			(at 191.15 225.35 0)
			(layer "B.Fab")
			(hide yes)
			(effects
				(font
					(size 1 1)
					(thickness 0.15)
				)
				(justify mirror)
			)
		)
		(property "DNP" ""
			(at 0 0 180)
			(unlocked yes)
			(layer "B.Fab")
			(hide yes)
			(effects
				(font
					(size 1 1)
					(thickness 0.15)
				)
				(justify mirror)
			)
		)
		(sheetname "/FPGA banks 13-16/")
		(sheetfile "fpga-banks-13-16.kicad_sch")
		(attr smd)
		(fp_rect
			(start -0.925 0.47)
			(end 0.925 -0.47)
			(stroke
				(width 0.05)
				(type default)
			)
			(fill no)
			(layer "B.CrtYd")
		)
		(fp_line
			(start 0.504 0.25)
			(end 0.504 -0.248)
			(stroke
				(width 0.15)
				(type solid)
			)
			(layer "B.Fab")
		)
		(fp_line
			(start 0.504 -0.248)
			(end -0.494 -0.248)
			(stroke
				(width 0.15)
				(type solid)
			)
			(layer "B.Fab")
		)
		(fp_line
			(start -0.494 0.25)
			(end 0.504 0.25)
			(stroke
				(width 0.15)
				(type solid)
			)
			(layer "B.Fab")
		)
		(fp_line
			(start -0.494 -0.248)
			(end -0.494 0.25)
			(stroke
				(width 0.15)
				(type solid)
			)
			(layer "B.Fab")
		)
		(pad "1" smd roundrect
			(at -0.48 0 180)
			(size 0.59 0.64)
			(layers "B.Cu" "B.Mask" "B.Paste")
			(roundrect_rratio 0.25)
			(net 1 "GND")
			(pintype "passive")
		)
		(pad "2" smd roundrect
			(at 0.48 0 180)
			(size 0.59 0.64)
			(layers "B.Cu" "B.Mask" "B.Paste")
			(roundrect_rratio 0.25)
			(net 2 "VCC3V3")
			(pintype "passive")
		)
	)
	(footprint "antmicro-footprints:C_0402_1005Metric"
		(layer "B.Cu")
		(at 96.575 115.675 180)
		(descr "Capacitor SMD 0402")
		(tags "capacitor SMD 0402")
		(property "Reference" "C111"
			(at -1.251 0.45 0)
			(layer "B.SilkS")
			(effects
				(font
					(size 0.7 0.7)
					(thickness 0.15)
				)
				(justify left bottom mirror)
			)
		)
		(property "Value" "C_470n_0402"
			(at 0 -1.4 0)
			(layer "B.Fab")
			(effects
				(font
					(size 0.7 0.7)
					(thickness 0.15)
				)
				(justify left bottom mirror)
			)
		)
		(property "Datasheet" "https://product.tdk.com/en/search/capacitor/ceramic/mlcc/info?part_no=C1005X5R1E474M050BB"
			(at 0 0 180)
			(layer "F.Fab")
			(hide yes)
			(effects
				(font
					(size 1.27 1.27)
					(thickness 0.15)
				)
			)
		)
		(property "Description" "SMD Multilayer Ceramic Capacitor, 0.47 µF, 25 V, 0402 [1005 Metric], ± 20%, X5R, C"
			(at 0 0 180)
			(layer "F.Fab")
			(hide yes)
			(effects
				(font
					(size 1.27 1.27)
					(thickness 0.15)
				)
			)
		)
		(property "Author" "Antmicro"
			(at 193.15 231.35 0)
			(layer "B.Fab")
			(hide yes)
			(effects
				(font
					(size 1 1)
					(thickness 0.15)
				)
				(justify mirror)
			)
		)
		(property "Dielectric" ""
			(at 193.15 231.35 0)
			(layer "B.Fab")
			(hide yes)
			(effects
				(font
					(size 1 1)
					(thickness 0.15)
				)
				(justify mirror)
			)
		)
		(property "License" "Apache-2.0"
			(at 193.15 231.35 0)
			(layer "B.Fab")
			(hide yes)
			(effects
				(font
					(size 1 1)
					(thickness 0.15)
				)
				(justify mirror)
			)
		)
		(property "MPN" "C1005X5R1E474M050BB"
			(at 193.15 231.35 0)
			(layer "B.Fab")
			(hide yes)
			(effects
				(font
					(size 1 1)
					(thickness 0.15)
				)
				(justify mirror)
			)
		)
		(property "Manufacturer" "TDK"
			(at 193.15 231.35 0)
			(layer "B.Fab")
			(hide yes)
			(effects
				(font
					(size 1 1)
					(thickness 0.15)
				)
				(justify mirror)
			)
		)
		(property "Val" "470n"
			(at 193.15 231.35 0)
			(layer "B.Fab")
			(hide yes)
			(effects
				(font
					(size 1 1)
					(thickness 0.15)
				)
				(justify mirror)
			)
		)
		(property "Voltage" ""
			(at 193.15 231.35 0)
			(layer "B.Fab")
			(hide yes)
			(effects
				(font
					(size 1 1)
					(thickness 0.15)
				)
				(justify mirror)
			)
		)
		(sheetname "/FPGA banks 13-16/")
		(sheetfile "fpga-banks-13-16.kicad_sch")
		(attr smd)
		(fp_rect
			(start -0.925 0.47)
			(end 0.925 -0.47)
			(stroke
				(width 0.05)
				(type default)
			)
			(fill no)
			(layer "B.CrtYd")
		)
		(fp_line
			(start 0.504 0.25)
			(end 0.504 -0.248)
			(stroke
				(width 0.15)
				(type solid)
			)
			(layer "B.Fab")
		)
		(fp_line
			(start 0.504 -0.248)
			(end -0.494 -0.248)
			(stroke
				(width 0.15)
				(type solid)
			)
			(layer "B.Fab")
		)
		(fp_line
			(start -0.494 0.25)
			(end 0.504 0.25)
			(stroke
				(width 0.15)
				(type solid)
			)
			(layer "B.Fab")
		)
		(fp_line
			(start -0.494 -0.248)
			(end -0.494 0.25)
			(stroke
				(width 0.15)
				(type solid)
			)
			(layer "B.Fab")
		)
		(pad "1" smd roundrect
			(at -0.48 0 180)
			(size 0.59 0.64)
			(layers "B.Cu" "B.Mask" "B.Paste")
			(roundrect_rratio 0.25)
			(net 1 "GND")
			(pintype "passive")
		)
		(pad "2" smd roundrect
			(at 0.48 0 180)
			(size 0.59 0.64)
			(layers "B.Cu" "B.Mask" "B.Paste")
			(roundrect_rratio 0.25)
			(net 2 "VCC3V3")
			(pintype "passive")
		)
	)
	(footprint "antmicro-footprints:C_0402_1005Metric"
		(layer "B.Cu")
		(at 96.275 118.475 -90)
		(descr "Capacitor SMD 0402")
		(tags "capacitor SMD 0402")
		(property "Reference" "C117"
			(at -1.575 0.475 90)
			(layer "B.SilkS")
			(effects
				(font
					(size 0.7 0.7)
					(thickness 0.15)
				)
				(justify left bottom mirror)
			)
		)
		(property "Value" "C_470n_0402"
			(at 0 -1.4 90)
			(layer "B.Fab")
			(effects
				(font
					(size 0.7 0.7)
					(thickness 0.15)
				)
				(justify left bottom mirror)
			)
		)
		(property "Datasheet" "https://product.tdk.com/en/search/capacitor/ceramic/mlcc/info?part_no=C1005X5R1E474M050BB"
			(at 0 0 270)
			(layer "F.Fab")
			(hide yes)
			(effects
				(font
					(size 1.27 1.27)
					(thickness 0.15)
				)
			)
		)
		(property "Description" "SMD Multilayer Ceramic Capacitor, 0.47 µF, 25 V, 0402 [1005 Metric], ± 20%, X5R, C"
			(at 0 0 270)
			(layer "F.Fab")
			(hide yes)
			(effects
				(font
					(size 1.27 1.27)
					(thickness 0.15)
				)
			)
		)
		(property "Author" "Antmicro"
			(at -22.2 214.75 0)
			(layer "B.Fab")
			(hide yes)
			(effects
				(font
					(size 1 1)
					(thickness 0.15)
				)
				(justify mirror)
			)
		)
		(property "Dielectric" ""
			(at -22.2 214.75 0)
			(layer "B.Fab")
			(hide yes)
			(effects
				(font
					(size 1 1)
					(thickness 0.15)
				)
				(justify mirror)
			)
		)
		(property "License" "Apache-2.0"
			(at -22.2 214.75 0)
			(layer "B.Fab")
			(hide yes)
			(effects
				(font
					(size 1 1)
					(thickness 0.15)
				)
				(justify mirror)
			)
		)
		(property "MPN" "C1005X5R1E474M050BB"
			(at -22.2 214.75 0)
			(layer "B.Fab")
			(hide yes)
			(effects
				(font
					(size 1 1)
					(thickness 0.15)
				)
				(justify mirror)
			)
		)
		(property "Manufacturer" "TDK"
			(at -22.2 214.75 0)
			(layer "B.Fab")
			(hide yes)
			(effects
				(font
					(size 1 1)
					(thickness 0.15)
				)
				(justify mirror)
			)
		)
		(property "Val" "470n"
			(at -22.2 214.75 0)
			(layer "B.Fab")
			(hide yes)
			(effects
				(font
					(size 1 1)
					(thickness 0.15)
				)
				(justify mirror)
			)
		)
		(property "Voltage" ""
			(at -22.2 214.75 0)
			(layer "B.Fab")
			(hide yes)
			(effects
				(font
					(size 1 1)
					(thickness 0.15)
				)
				(justify mirror)
			)
		)
		(property "DNP" ""
			(at 0 0 270)
			(unlocked yes)
			(layer "B.Fab")
			(hide yes)
			(effects
				(font
					(size 1 1)
					(thickness 0.15)
				)
				(justify mirror)
			)
		)
		(sheetname "/FPGA banks 13-16/")
		(sheetfile "fpga-banks-13-16.kicad_sch")
		(attr smd)
		(fp_rect
			(start -0.925 0.47)
			(end 0.925 -0.47)
			(stroke
				(width 0.05)
				(type default)
			)
			(fill no)
			(layer "B.CrtYd")
		)
		(fp_line
			(start -0.494 0.25)
			(end 0.504 0.25)
			(stroke
				(width 0.15)
				(type solid)
			)
			(layer "B.Fab")
		)
		(fp_line
			(start 0.504 0.25)
			(end 0.504 -0.248)
			(stroke
				(width 0.15)
				(type solid)
			)
			(layer "B.Fab")
		)
		(fp_line
			(start -0.494 -0.248)
			(end -0.494 0.25)
			(stroke
				(width 0.15)
				(type solid)
			)
			(layer "B.Fab")
		)
		(fp_line
			(start 0.504 -0.248)
			(end -0.494 -0.248)
			(stroke
				(width 0.15)
				(type solid)
			)
			(layer "B.Fab")
		)
		(pad "1" smd roundrect
			(at -0.48 0 270)
			(size 0.59 0.64)
			(layers "B.Cu" "B.Mask" "B.Paste")
			(roundrect_rratio 0.25)
			(net 1 "GND")
			(pintype "passive")
		)
		(pad "2" smd roundrect
			(at 0.48 0 270)
			(size 0.59 0.64)
			(layers "B.Cu" "B.Mask" "B.Paste")
			(roundrect_rratio 0.25)
			(net 2 "VCC3V3")
			(pintype "passive")
		)
	)
	(footprint "antmicro-footprints:C_0402_1005Metric"
		(layer "B.Cu")
		(at 92.275 109.675)
		(descr "Capacitor SMD 0402")
		(tags "capacitor SMD 0402")
		(property "Reference" "C123"
			(at -3.675 0.325 0)
			(layer "B.SilkS")
			(effects
				(font
					(size 0.7 0.7)
					(thickness 0.15)
				)
				(justify right bottom mirror)
			)
		)
		(property "Value" "C_470n_0402"
			(at 0 -1.4 0)
			(layer "B.Fab")
			(effects
				(font
					(size 0.7 0.7)
					(thickness 0.15)
				)
				(justify right bottom mirror)
			)
		)
		(property "Datasheet" "https://product.tdk.com/en/search/capacitor/ceramic/mlcc/info?part_no=C1005X5R1E474M050BB"
			(at 0 0 0)
			(layer "F.Fab")
			(hide yes)
			(effects
				(font
					(size 1.27 1.27)
					(thickness 0.15)
				)
			)
		)
		(property "Description" "SMD Multilayer Ceramic Capacitor, 0.47 µF, 25 V, 0402 [1005 Metric], ± 20%, X5R, C"
			(at 0 0 0)
			(layer "F.Fab")
			(hide yes)
			(effects
				(font
					(size 1.27 1.27)
					(thickness 0.15)
				)
			)
		)
		(property "Author" "Antmicro"
			(at 0 0 0)
			(layer "B.Fab")
			(hide yes)
			(effects
				(font
					(size 1 1)
					(thickness 0.15)
				)
				(justify mirror)
			)
		)
		(property "Dielectric" ""
			(at 0 0 0)
			(layer "B.Fab")
			(hide yes)
			(effects
				(font
					(size 1 1)
					(thickness 0.15)
				)
				(justify mirror)
			)
		)
		(property "License" "Apache-2.0"
			(at 0 0 0)
			(layer "B.Fab")
			(hide yes)
			(effects
				(font
					(size 1 1)
					(thickness 0.15)
				)
				(justify mirror)
			)
		)
		(property "MPN" "C1005X5R1E474M050BB"
			(at 0 0 0)
			(layer "B.Fab")
			(hide yes)
			(effects
				(font
					(size 1 1)
					(thickness 0.15)
				)
				(justify mirror)
			)
		)
		(property "Manufacturer" "TDK"
			(at 0 0 0)
			(layer "B.Fab")
			(hide yes)
			(effects
				(font
					(size 1 1)
					(thickness 0.15)
				)
				(justify mirror)
			)
		)
		(property "Val" "470n"
			(at 0 0 0)
			(layer "B.Fab")
			(hide yes)
			(effects
				(font
					(size 1 1)
					(thickness 0.15)
				)
				(justify mirror)
			)
		)
		(property "Voltage" ""
			(at 0 0 0)
			(layer "B.Fab")
			(hide yes)
			(effects
				(font
					(size 1 1)
					(thickness 0.15)
				)
				(justify mirror)
			)
		)
		(sheetname "/FPGA banks 13-16/")
		(sheetfile "fpga-banks-13-16.kicad_sch")
		(attr smd)
		(fp_rect
			(start -0.925 0.47)
			(end 0.925 -0.47)
			(stroke
				(width 0.05)
				(type default)
			)
			(fill no)
			(layer "B.CrtYd")
		)
		(fp_line
			(start -0.494 -0.248)
			(end -0.494 0.25)
			(stroke
				(width 0.15)
				(type solid)
			)
			(layer "B.Fab")
		)
		(fp_line
			(start -0.494 0.25)
			(end 0.504 0.25)
			(stroke
				(width 0.15)
				(type solid)
			)
			(layer "B.Fab")
		)
		(fp_line
			(start 0.504 -0.248)
			(end -0.494 -0.248)
			(stroke
				(width 0.15)
				(type solid)
			)
			(layer "B.Fab")
		)
		(fp_line
			(start 0.504 0.25)
			(end 0.504 -0.248)
			(stroke
				(width 0.15)
				(type solid)
			)
			(layer "B.Fab")
		)
		(pad "1" smd roundrect
			(at -0.48 0)
			(size 0.59 0.64)
			(layers "B.Cu" "B.Mask" "B.Paste")
			(roundrect_rratio 0.25)
			(net 1 "GND")
			(pintype "passive")
		)
		(pad "2" smd roundrect
			(at 0.48 0)
			(size 0.59 0.64)
			(layers "B.Cu" "B.Mask" "B.Paste")
			(roundrect_rratio 0.25)
			(net 2 "VCC3V3")
			(pintype "passive")
		)
	)
	(footprint "antmicro-footprints:C_0402_1005Metric"
		(layer "B.Cu")
		(at 98.775 109.675)
		(descr "Capacitor SMD 0402")
		(tags "capacitor SMD 0402")
		(property "Reference" "C112"
			(at -0.875 -0.575 0)
			(layer "B.SilkS")
			(effects
				(font
					(size 0.7 0.7)
					(thickness 0.15)
				)
				(justify right bottom mirror)
			)
		)
		(property "Value" "C_470n_0402"
			(at 0 -1.4 0)
			(layer "B.Fab")
			(effects
				(font
					(size 0.7 0.7)
					(thickness 0.15)
				)
				(justify right bottom mirror)
			)
		)
		(property "Datasheet" "https://product.tdk.com/en/search/capacitor/ceramic/mlcc/info?part_no=C1005X5R1E474M050BB"
			(at 0 0 0)
			(layer "F.Fab")
			(hide yes)
			(effects
				(font
					(size 1.27 1.27)
					(thickness 0.15)
				)
			)
		)
		(property "Description" "SMD Multilayer Ceramic Capacitor, 0.47 µF, 25 V, 0402 [1005 Metric], ± 20%, X5R, C"
			(at 0 0 0)
			(layer "F.Fab")
			(hide yes)
			(effects
				(font
					(size 1.27 1.27)
					(thickness 0.15)
				)
			)
		)
		(property "Author" "Antmicro"
			(at 0 0 0)
			(layer "B.Fab")
			(hide yes)
			(effects
				(font
					(size 1 1)
					(thickness 0.15)
				)
				(justify mirror)
			)
		)
		(property "Dielectric" ""
			(at 0 0 0)
			(layer "B.Fab")
			(hide yes)
			(effects
				(font
					(size 1 1)
					(thickness 0.15)
				)
				(justify mirror)
			)
		)
		(property "License" "Apache-2.0"
			(at 0 0 0)
			(layer "B.Fab")
			(hide yes)
			(effects
				(font
					(size 1 1)
					(thickness 0.15)
				)
				(justify mirror)
			)
		)
		(property "MPN" "C1005X5R1E474M050BB"
			(at 0 0 0)
			(layer "B.Fab")
			(hide yes)
			(effects
				(font
					(size 1 1)
					(thickness 0.15)
				)
				(justify mirror)
			)
		)
		(property "Manufacturer" "TDK"
			(at 0 0 0)
			(layer "B.Fab")
			(hide yes)
			(effects
				(font
					(size 1 1)
					(thickness 0.15)
				)
				(justify mirror)
			)
		)
		(property "Val" "470n"
			(at 0 0 0)
			(layer "B.Fab")
			(hide yes)
			(effects
				(font
					(size 1 1)
					(thickness 0.15)
				)
				(justify mirror)
			)
		)
		(property "Voltage" ""
			(at 0 0 0)
			(layer "B.Fab")
			(hide yes)
			(effects
				(font
					(size 1 1)
					(thickness 0.15)
				)
				(justify mirror)
			)
		)
		(property "DNP" ""
			(at 0 0 0)
			(unlocked yes)
			(layer "B.Fab")
			(hide yes)
			(effects
				(font
					(size 1 1)
					(thickness 0.15)
				)
				(justify mirror)
			)
		)
		(sheetname "/FPGA banks 13-16/")
		(sheetfile "fpga-banks-13-16.kicad_sch")
		(attr smd)
		(fp_rect
			(start -0.925 0.47)
			(end 0.925 -0.47)
			(stroke
				(width 0.05)
				(type default)
			)
			(fill no)
			(layer "B.CrtYd")
		)
		(fp_line
			(start -0.494 -0.248)
			(end -0.494 0.25)
			(stroke
				(width 0.15)
				(type solid)
			)
			(layer "B.Fab")
		)
		(fp_line
			(start -0.494 0.25)
			(end 0.504 0.25)
			(stroke
				(width 0.15)
				(type solid)
			)
			(layer "B.Fab")
		)
		(fp_line
			(start 0.504 -0.248)
			(end -0.494 -0.248)
			(stroke
				(width 0.15)
				(type solid)
			)
			(layer "B.Fab")
		)
		(fp_line
			(start 0.504 0.25)
			(end 0.504 -0.248)
			(stroke
				(width 0.15)
				(type solid)
			)
			(layer "B.Fab")
		)
		(pad "1" smd roundrect
			(at -0.48 0)
			(size 0.59 0.64)
			(layers "B.Cu" "B.Mask" "B.Paste")
			(roundrect_rratio 0.25)
			(net 1 "GND")
			(pintype "passive")
		)
		(pad "2" smd roundrect
			(at 0.48 0)
			(size 0.59 0.64)
			(layers "B.Cu" "B.Mask" "B.Paste")
			(roundrect_rratio 0.25)
			(net 2 "VCC3V3")
			(pintype "passive")
		)
	)
)
